(kicad_pcb
	(version 20260206)
	(generator "pcbnew")
	(generator_version "10.0")
	(general
		(thickness 1.6)
		(legacy_teardrops no)
	)
	(paper "A4")
	(title_block
		(title "v1-chassis-manager — T6M_CM_d_v01_1031_1645.brd")
		(comment 1 "Open CloudServer (Microsoft) / footprint 1507 of 2512 (U2), pads 831-948 of 1283")
	)
	(layers
		(0 "F.Cu" signal "TOP")
		(4 "In1.Cu" signal "GND1")
		(6 "In2.Cu" signal "IN1")
		(8 "In3.Cu" signal "VCC1")
		(10 "In4.Cu" signal "VCC2")
		(12 "In5.Cu" signal "GND2")
		(14 "In6.Cu" signal "IN2")
		(16 "In7.Cu" signal "IN3")
		(18 "In8.Cu" signal "GND3")
		(2 "B.Cu" signal "BOTTOM")
		(9 "F.Adhes" user "F.Adhesive")
		(11 "B.Adhes" user "B.Adhesive")
		(13 "F.Paste" user "Package Geometry/Pastemask Top")
		(15 "B.Paste" user "Package Geometry/Pastemask Bottom")
		(5 "F.SilkS" user "Ref Des/Silkscreen Top")
		(7 "B.SilkS" user "Ref Des/Silkscreen Bottom")
		(1 "F.Mask" user "Board Geometry/Soldermask Top")
		(3 "B.Mask" user "Board Geometry/Soldermask Bottom")
		(17 "Dwgs.User" user "User.Drawings")
		(19 "Cmts.User" user "User.Comments")
		(21 "Eco1.User" user "User.Eco1")
		(23 "Eco2.User" user "User.Eco2")
		(25 "Edge.Cuts" user "Board Geometry/Outline")
		(27 "Margin" user)
		(31 "F.CrtYd" user "Package Geometry/Place Bound Top")
		(29 "B.CrtYd" user "Package Geometry/Place Bound Bottom")
		(35 "F.Fab" user "Ref Des/Assembly Top")
		(33 "B.Fab" user "Ref Des/Assembly Bottom")
	)
	(footprint ""
		(layer "F.Cu")
		(at 58.000646 -75.799442)
		(property "Reference" "U2"
			(at -20.2438 -18.364708 0)
			(unlocked yes)
			(layer "F.SilkS")
			(effects
				(font
					(size 1.6002 1.1938)
					(thickness 0.1524)
				)
				(justify left)
			)
		)
		(property "Value" ""
			(at 0 0 0)
			(layer "F.Fab")
			(effects
				(font
					(size 1.27 1.27)
				)
			)
		)
		(duplicate_pad_numbers_are_jumpers no)
		(pad "BP8" smd oval
			(at -12.859766 13.110972)
			(size 0.2794 0.3429)
			(layers "F.Cu" "F.Mask" "F.Paste")
			(net "GND")
		)
		(pad "BP10" smd oval
			(at -11.966702 13.249402)
			(size 0.254 0.3429)
			(layers "F.Cu" "F.Mask" "F.Paste")
			(net "GND")
		)
		(pad "BP13" smd oval
			(at -10.341102 13.249402)
			(size 0.254 0.3429)
			(layers "F.Cu" "F.Mask" "F.Paste")
			(net "M1_DQ_NODE1_DQ12")
		)
		(pad "BP16" smd oval
			(at -8.902446 13.249402)
			(size 0.254 0.3429)
			(layers "F.Cu" "F.Mask" "F.Paste")
			(net "GND")
		)
		(pad "BP19" smd oval
			(at -7.46379 13.249402)
			(size 0.254 0.3429)
			(layers "F.Cu" "F.Mask" "F.Paste")
			(net "GND")
		)
		(pad "BP22" smd oval
			(at -5.83819 13.249402)
			(size 0.254 0.3429)
			(layers "F.Cu" "F.Mask" "F.Paste")
			(net "M1_DQ_NODE1_DQ28")
		)
		(pad "BP25" smd oval
			(at -4.399534 13.249402)
			(size 0.254 0.3429)
			(layers "F.Cu" "F.Mask" "F.Paste")
			(net "GND")
		)
		(pad "BP28" smd oval
			(at -2.960878 13.249402)
			(size 0.254 0.3429)
			(layers "F.Cu" "F.Mask" "F.Paste")
			(net "GND")
		)
		(pad "BP31" smd oval
			(at -1.335278 13.249402)
			(size 0.254 0.3429)
			(layers "F.Cu" "F.Mask" "F.Paste")
			(net "M_DDR3_NODE1_MA15")
		)
		(pad "BP34" smd oval
			(at 0.103378 13.249402)
			(size 0.254 0.3429)
			(layers "F.Cu" "F.Mask" "F.Paste")
			(net "PV_VDDR_NODE1")
		)
		(pad "BP37" smd oval
			(at 1.542034 13.249402)
			(size 0.254 0.3429)
			(layers "F.Cu" "F.Mask" "F.Paste")
			(net "M_DDR3_NODE1_MA6")
		)
		(pad "BP40" smd oval
			(at 3.167634 13.249402)
			(size 0.254 0.3429)
			(layers "F.Cu" "F.Mask" "F.Paste")
			(net "M_DDR3_NODE1_MA2")
		)
		(pad "BP43" smd oval
			(at 4.60629 13.249402)
			(size 0.254 0.3429)
			(layers "F.Cu" "F.Mask" "F.Paste")
			(net "M_DDR3_NODE1_RAS_L")
		)
		(pad "BP46" smd oval
			(at 6.044946 13.249402)
			(size 0.254 0.3429)
			(layers "F.Cu" "F.Mask" "F.Paste")
			(net "M_DDR3_NODE1_CS1_L")
		)
		(pad "BP49" smd oval
			(at 7.670546 13.249402)
			(size 0.254 0.3429)
			(layers "F.Cu" "F.Mask" "F.Paste")
			(net "M_DDR3_NODE1_ODT1")
		)
		(pad "BP52" smd oval
			(at 9.109202 13.249402)
			(size 0.254 0.3429)
			(layers "F.Cu" "F.Mask" "F.Paste")
			(net "GND")
		)
		(pad "BP55" smd oval
			(at 10.547858 13.249402)
			(size 0.254 0.3429)
			(layers "F.Cu" "F.Mask" "F.Paste")
			(net "GND")
		)
		(pad "BP58" smd oval
			(at 12.173458 13.249402)
			(size 0.254 0.3429)
			(layers "F.Cu" "F.Mask" "F.Paste")
			(net "GND")
		)
		(pad "BP59" smd oval
			(at 12.859766 13.110972)
			(size 0.2794 0.3429)
			(layers "F.Cu" "F.Mask" "F.Paste")
			(net "GND")
		)
		(pad "BP61" smd circle
			(at 13.672566 13.110972)
			(size 0.4064 0.4064)
			(layers "F.Cu" "F.Mask" "F.Paste")
			(net "GND")
		)
		(pad "BP62" smd circle
			(at 14.485366 13.110972)
			(size 0.4064 0.4064)
			(layers "F.Cu" "F.Mask" "F.Paste")
			(net "GND")
		)
		(pad "BP64" smd circle
			(at 15.298166 13.110972)
			(size 0.4064 0.4064)
			(layers "F.Cu" "F.Mask" "F.Paste")
			(net "GND")
		)
		(pad "BP66" smd circle
			(at 16.110966 13.110972)
			(size 0.4064 0.4064)
			(layers "F.Cu" "F.Mask" "F.Paste")
			(net "GND")
		)
		(pad "C3" smd circle
			(at -15.298166 -12.298172)
			(size 0.4064 0.4064)
			(layers "F.Cu" "F.Mask" "F.Paste")
			(net "GND")
		)
		(pad "C5" smd circle
			(at -14.485366 -12.298172)
			(size 0.4064 0.4064)
			(layers "F.Cu" "F.Mask" "F.Paste")
			(net "GND")
		)
		(pad "C6" smd circle
			(at -13.612368 -12.304522)
			(size 0.3048 0.3048)
			(layers "F.Cu" "F.Mask" "F.Paste")
			(net "GND")
		)
		(pad "C9" smd circle
			(at -12.403836 -12.2428)
			(size 0.3048 0.3048)
			(layers "F.Cu" "F.Mask" "F.Paste")
			(net "GND")
		)
		(pad "C13" smd circle
			(at -10.29208 -12.247118)
			(size 0.3048 0.3048)
			(layers "F.Cu" "F.Mask" "F.Paste")
			(net "GND")
		)
		(pad "C15" smd circle
			(at -9.058402 -12.304522)
			(size 0.3048 0.3048)
			(layers "F.Cu" "F.Mask" "F.Paste")
			(net "PD_NODE1_NTB_PERP")
		)
		(pad "C18" smd circle
			(at -7.900924 -12.2428)
			(size 0.3048 0.3048)
			(layers "F.Cu" "F.Mask" "F.Paste")
			(net "GND")
		)
		(pad "C22" smd circle
			(at -5.789168 -12.247118)
			(size 0.3048 0.3048)
			(layers "F.Cu" "F.Mask" "F.Paste")
			(net "GND")
		)
		(pad "C24" smd circle
			(at -4.55549 -12.304522)
			(size 0.3048 0.3048)
			(layers "F.Cu" "F.Mask" "F.Paste")
			(net "PD_NODE1_NTB_PERP")
		)
		(pad "C27" smd circle
			(at -3.398012 -12.2428)
			(size 0.3048 0.3048)
			(layers "F.Cu" "F.Mask" "F.Paste")
			(net "GND")
		)
		(pad "C31" smd circle
			(at -1.286256 -12.247118)
			(size 0.3048 0.3048)
			(layers "F.Cu" "F.Mask" "F.Paste")
			(net "PU_CPU_NODE1_DFX_GPIO_GRP1_6")
		)
		(pad "C33" smd circle
			(at -0.052578 -12.304522)
			(size 0.3048 0.3048)
			(layers "F.Cu" "F.Mask" "F.Paste")
			(net "PD_CPU_NODE1_DFX_GPIO_GRP1_0")
		)
		(pad "C36" smd circle
			(at 1.1049 -12.2428)
			(size 0.3048 0.3048)
			(layers "F.Cu" "F.Mask" "F.Paste")
			(net "TP_CPU0_NODE1_SFRANAD")
		)
		(pad "C40" smd circle
			(at 3.216656 -12.247118)
			(size 0.3048 0.3048)
			(layers "F.Cu" "F.Mask" "F.Paste")
			(net "SPI_CPU_NODE1_CS0_R_L")
		)
		(pad "C42" smd circle
			(at 4.450334 -12.304522)
			(size 0.3048 0.3048)
			(layers "F.Cu" "F.Mask" "F.Paste")
			(net "LPC_CPU_NODE1_CLKRUN_L")
		)
		(pad "C45" smd circle
			(at 5.607812 -12.2428)
			(size 0.3048 0.3048)
			(layers "F.Cu" "F.Mask" "F.Paste")
			(net "LPC_CPU_NODE1_R_CLKOUT1")
		)
		(pad "C49" smd circle
			(at 7.719568 -12.247118)
			(size 0.3048 0.3048)
			(layers "F.Cu" "F.Mask" "F.Paste")
			(net "SPC_CPU_NODE1_CTS_L")
		)
		(pad "C51" smd circle
			(at 8.953246 -12.304522)
			(size 0.3048 0.3048)
			(layers "F.Cu" "F.Mask" "F.Paste")
			(net "H_CPU_NODE1_ERR2_R")
		)
		(pad "C54" smd circle
			(at 10.110724 -12.2428)
			(size 0.3048 0.3048)
			(layers "F.Cu" "F.Mask" "F.Paste")
			(net "GND")
		)
		(pad "C58" smd circle
			(at 12.22248 -12.247118)
			(size 0.3048 0.3048)
			(layers "F.Cu" "F.Mask" "F.Paste")
			(net "GND")
		)
		(pad "C60" smd circle
			(at 13.405358 -12.304522)
			(size 0.3048 0.3048)
			(layers "F.Cu" "F.Mask" "F.Paste")
			(net "GND")
		)
		(pad "C62" smd circle
			(at 14.485366 -12.298172)
			(size 0.4064 0.4064)
			(layers "F.Cu" "F.Mask" "F.Paste")
			(net "GND")
		)
		(pad "C64" smd circle
			(at 15.298166 -12.298172)
			(size 0.4064 0.4064)
			(layers "F.Cu" "F.Mask" "F.Paste")
			(net "GND")
		)
		(pad "C66" smd circle
			(at 16.110966 -12.298172)
			(size 0.4064 0.4064)
			(layers "F.Cu" "F.Mask" "F.Paste")
			(net "GND")
		)
		(pad "D6" smd circle
			(at -13.612368 -11.542522)
			(size 0.3048 0.3048)
			(layers "F.Cu" "F.Mask" "F.Paste")
			(net "GND")
		)
		(pad "D8" smd circle
			(at -12.932664 -11.751564)
			(size 0.3048 0.3048)
			(layers "F.Cu" "F.Mask" "F.Paste")
			(net "GND")
		)
		(pad "D10" smd circle
			(at -11.792458 -11.900916)
			(size 0.3048 0.3048)
			(layers "F.Cu" "F.Mask" "F.Paste")
			(net "PD_NODE1_NTB_PERN")
		)
		(pad "D12" smd circle
			(at -10.903458 -11.900916)
			(size 0.3048 0.3048)
			(layers "F.Cu" "F.Mask" "F.Paste")
			(net "PD_NODE1_NTB_PERN")
		)
		(pad "D14" smd circle
			(at -9.788906 -11.751564)
			(size 0.3048 0.3048)
			(layers "F.Cu" "F.Mask" "F.Paste")
			(net "GND")
		)
		(pad "D15" smd circle
			(at -9.109202 -11.542522)
			(size 0.3048 0.3048)
			(layers "F.Cu" "F.Mask" "F.Paste")
			(net "PD_NODE1_NTB_PERN")
		)
		(pad "D17" smd circle
			(at -8.440674 -11.794744)
			(size 0.3048 0.3048)
			(layers "F.Cu" "F.Mask" "F.Paste")
			(net "PD_NODE1_NTB_PERN")
		)
		(pad "D19" smd circle
			(at -7.289546 -11.900916)
			(size 0.3048 0.3048)
			(layers "F.Cu" "F.Mask" "F.Paste")
			(net "PD_NODE1_NTB_PERP")
		)
		(pad "D21" smd circle
			(at -6.400546 -11.900916)
			(size 0.3048 0.3048)
			(layers "F.Cu" "F.Mask" "F.Paste")
			(net "PD_NODE1_NTB_PERP")
		)
		(pad "D23" smd circle
			(at -5.285994 -11.751564)
			(size 0.3048 0.3048)
			(layers "F.Cu" "F.Mask" "F.Paste")
			(net "PD_NODE1_NTB_PERP")
		)
		(pad "D24" smd circle
			(at -4.60629 -11.542522)
			(size 0.3048 0.3048)
			(layers "F.Cu" "F.Mask" "F.Paste")
			(net "PD_NODE1_NTB_PERP")
		)
		(pad "D26" smd circle
			(at -3.937762 -11.794744)
			(size 0.3048 0.3048)
			(layers "F.Cu" "F.Mask" "F.Paste")
			(net "PD_NODE1_NTB_PERN")
		)
		(pad "D28" smd circle
			(at -2.786634 -11.900916)
			(size 0.3048 0.3048)
			(layers "F.Cu" "F.Mask" "F.Paste")
			(net "PD_CPU_NODE1_DFX_GPIO_GRP0_1")
		)
		(pad "D30" smd circle
			(at -1.897634 -11.900916)
			(size 0.3048 0.3048)
			(layers "F.Cu" "F.Mask" "F.Paste")
			(net "PD_CPU_NODE1_DFX_GPIO_GRP0_0")
		)
		(pad "D32" smd circle
			(at -0.783082 -11.751564)
			(size 0.3048 0.3048)
			(layers "F.Cu" "F.Mask" "F.Paste")
			(net "GND")
		)
		(pad "D33" smd circle
			(at -0.103378 -11.542522)
			(size 0.3048 0.3048)
			(layers "F.Cu" "F.Mask" "F.Paste")
			(net "PD_CPU_NODE1_DFX_GPIO_GRP1_1")
		)
		(pad "D35" smd circle
			(at 0.56515 -11.794744)
			(size 0.3048 0.3048)
			(layers "F.Cu" "F.Mask" "F.Paste")
			(net "TP_CPU1_NODE1_SFRANAD")
		)
		(pad "D37" smd circle
			(at 1.716278 -11.900916)
			(size 0.3048 0.3048)
			(layers "F.Cu" "F.Mask" "F.Paste")
			(net "GND")
		)
		(pad "D39" smd circle
			(at 2.605278 -11.900916)
			(size 0.3048 0.3048)
			(layers "F.Cu" "F.Mask" "F.Paste")
			(net "GND")
		)
		(pad "D41" smd circle
			(at 3.71983 -11.751564)
			(size 0.3048 0.3048)
			(layers "F.Cu" "F.Mask" "F.Paste")
			(net "GND")
		)
		(pad "D42" smd circle
			(at 4.399534 -11.542522)
			(size 0.3048 0.3048)
			(layers "F.Cu" "F.Mask" "F.Paste")
			(net "SPI_CPU_NODE1_MOSI_R")
		)
		(pad "D44" smd circle
			(at 5.068062 -11.794744)
			(size 0.3048 0.3048)
			(layers "F.Cu" "F.Mask" "F.Paste")
			(net "LPC_CPU_NODE1_FRAME_L_R")
		)
		(pad "D46" smd circle
			(at 6.21919 -11.900916)
			(size 0.3048 0.3048)
			(layers "F.Cu" "F.Mask" "F.Paste")
			(net "GND")
		)
		(pad "D48" smd circle
			(at 7.10819 -11.900916)
			(size 0.3048 0.3048)
			(layers "F.Cu" "F.Mask" "F.Paste")
			(net "Net_295")
		)
		(pad "D50" smd circle
			(at 8.222742 -11.751564)
			(size 0.3048 0.3048)
			(layers "F.Cu" "F.Mask" "F.Paste")
			(net "GND")
		)
		(pad "D51" smd circle
			(at 8.902446 -11.542522)
			(size 0.3048 0.3048)
			(layers "F.Cu" "F.Mask" "F.Paste")
			(net "H_CPU_NODE1_ERR1_R")
		)
		(pad "D53" smd circle
			(at 9.570974 -11.794744)
			(size 0.3048 0.3048)
			(layers "F.Cu" "F.Mask" "F.Paste")
			(net "TP_CPU_D53")
		)
		(pad "D55" smd circle
			(at 10.722102 -11.900916)
			(size 0.3048 0.3048)
			(layers "F.Cu" "F.Mask" "F.Paste")
			(net "PD_CPU_NODE1_NODE_ID")
		)
		(pad "D57" smd circle
			(at 11.611102 -11.900916)
			(size 0.3048 0.3048)
			(layers "F.Cu" "F.Mask" "F.Paste")
			(net "LAN2_DISABLE_N")
		)
		(pad "D59" smd circle
			(at 12.725654 -11.751564)
			(size 0.3048 0.3048)
			(layers "F.Cu" "F.Mask" "F.Paste")
			(net "GND")
		)
		(pad "D60" smd circle
			(at 13.405358 -11.542522)
			(size 0.3048 0.3048)
			(layers "F.Cu" "F.Mask" "F.Paste")
			(net "GND")
		)
		(pad "E1" smd circle
			(at -16.110966 -11.485372)
			(size 0.4064 0.4064)
			(layers "F.Cu" "F.Mask" "F.Paste")
			(net "GND")
		)
		(pad "E3" smd circle
			(at -15.298166 -11.485372)
			(size 0.4064 0.4064)
			(layers "F.Cu" "F.Mask" "F.Paste")
			(net "GND")
		)
		(pad "E5" smd circle
			(at -14.485366 -11.485372)
			(size 0.4064 0.4064)
			(layers "F.Cu" "F.Mask" "F.Paste")
			(net "GND")
		)
		(pad "E7" smd circle
			(at -13.101574 -11.063224)
			(size 0.3048 0.3048)
			(layers "F.Cu" "F.Mask" "F.Paste")
			(net "GND")
		)
		(pad "E9" smd circle
			(at -12.39393 -11.080496)
			(size 0.3048 0.3048)
			(layers "F.Cu" "F.Mask" "F.Paste")
			(net "GND")
		)
		(pad "E10" smd circle
			(at -11.70051 -11.204448)
			(size 0.3048 0.3048)
			(layers "F.Cu" "F.Mask" "F.Paste")
			(net "PD_NODE1_NTB_PERP")
		)
		(pad "E12" smd circle
			(at -11.000486 -11.204448)
			(size 0.3048 0.3048)
			(layers "F.Cu" "F.Mask" "F.Paste")
			(net "PD_NODE1_NTB_PERP")
		)
		(pad "E13" smd circle
			(at -10.322306 -11.013694)
			(size 0.3048 0.3048)
			(layers "F.Cu" "F.Mask" "F.Paste")
			(net "GND")
		)
		(pad "E14" smd circle
			(at -9.619996 -11.063224)
			(size 0.3048 0.3048)
			(layers "F.Cu" "F.Mask" "F.Paste")
			(net "GND")
		)
		(pad "E16" smd circle
			(at -8.598408 -11.063224)
			(size 0.3048 0.3048)
			(layers "F.Cu" "F.Mask" "F.Paste")
			(net "GND")
		)
		(pad "E18" smd circle
			(at -7.891018 -11.080496)
			(size 0.3048 0.3048)
			(layers "F.Cu" "F.Mask" "F.Paste")
			(net "GND")
		)
		(pad "E19" smd circle
			(at -7.197598 -11.204448)
			(size 0.3048 0.3048)
			(layers "F.Cu" "F.Mask" "F.Paste")
			(net "PD_NODE1_NTB_PERP")
		)
		(pad "E21" smd circle
			(at -6.497574 -11.204448)
			(size 0.3048 0.3048)
			(layers "F.Cu" "F.Mask" "F.Paste")
			(net "PD_NODE1_NTB_PERN")
		)
		(pad "E22" smd circle
			(at -5.819394 -11.013694)
			(size 0.3048 0.3048)
			(layers "F.Cu" "F.Mask" "F.Paste")
			(net "GND")
		)
		(pad "E23" smd circle
			(at -5.117084 -11.063224)
			(size 0.3048 0.3048)
			(layers "F.Cu" "F.Mask" "F.Paste")
			(net "PD_NODE1_NTB_PERN")
		)
		(pad "E25" smd circle
			(at -4.095496 -11.063224)
			(size 0.3048 0.3048)
			(layers "F.Cu" "F.Mask" "F.Paste")
			(net "GND")
		)
		(pad "E27" smd circle
			(at -3.388106 -11.080496)
			(size 0.3048 0.3048)
			(layers "F.Cu" "F.Mask" "F.Paste")
			(net "GND")
		)
		(pad "E28" smd circle
			(at -2.694686 -11.204448)
			(size 0.3048 0.3048)
			(layers "F.Cu" "F.Mask" "F.Paste")
			(net "PD_CPU_NODE1_DFX_GPIO_GRP0_6")
		)
		(pad "E30" smd circle
			(at -1.994662 -11.204448)
			(size 0.3048 0.3048)
			(layers "F.Cu" "F.Mask" "F.Paste")
			(net "GND")
		)
		(pad "E31" smd circle
			(at -1.316482 -11.013694)
			(size 0.3048 0.3048)
			(layers "F.Cu" "F.Mask" "F.Paste")
			(net "PU_CPU_NODE1_DFX_GPIO_GRP1_5")
		)
		(pad "E32" smd circle
			(at -0.614172 -11.063224)
			(size 0.3048 0.3048)
			(layers "F.Cu" "F.Mask" "F.Paste")
			(net "GND")
		)
		(pad "E34" smd circle
			(at 0.407416 -11.063224)
			(size 0.3048 0.3048)
			(layers "F.Cu" "F.Mask" "F.Paste")
			(net "GND")
		)
		(pad "E36" smd circle
			(at 1.114806 -11.073638)
			(size 0.3048 0.3048)
			(layers "F.Cu" "F.Mask" "F.Paste")
			(net "TP_CPU_NODE1_EXTBGREF")
		)
		(pad "E37" smd circle
			(at 1.808226 -11.204448)
			(size 0.3048 0.3048)
			(layers "F.Cu" "F.Mask" "F.Paste")
			(net "GND")
		)
		(pad "E39" smd circle
			(at 2.50825 -11.204448)
			(size 0.3048 0.3048)
			(layers "F.Cu" "F.Mask" "F.Paste")
			(net "TP_SPI_CPU_NODE1_CS1_L")
		)
		(pad "E40" smd circle
			(at 3.18643 -11.013694)
			(size 0.3048 0.3048)
			(layers "F.Cu" "F.Mask" "F.Paste")
			(net "SPI_CPU_NODE1_MISO")
		)
		(pad "E41" smd circle
			(at 3.88874 -11.063224)
			(size 0.3048 0.3048)
			(layers "F.Cu" "F.Mask" "F.Paste")
			(net "GND")
		)
		(pad "E43" smd circle
			(at 4.910328 -11.063224)
			(size 0.3048 0.3048)
			(layers "F.Cu" "F.Mask" "F.Paste")
			(net "GND")
		)
		(pad "E45" smd circle
			(at 5.617718 -11.080496)
			(size 0.3048 0.3048)
			(layers "F.Cu" "F.Mask" "F.Paste")
			(net "GND")
		)
		(pad "E46" smd circle
			(at 6.311138 -11.204448)
			(size 0.3048 0.3048)
			(layers "F.Cu" "F.Mask" "F.Paste")
			(net "GND")
		)
		(pad "E48" smd circle
			(at 7.011162 -11.204448)
			(size 0.3048 0.3048)
			(layers "F.Cu" "F.Mask" "F.Paste")
			(net "Net_297")
		)
		(pad "E49" smd circle
			(at 7.689342 -11.013694)
			(size 0.3048 0.3048)
			(layers "F.Cu" "F.Mask" "F.Paste")
			(net "Net_300")
		)
		(pad "E50" smd circle
			(at 8.391652 -11.063224)
			(size 0.3048 0.3048)
			(layers "F.Cu" "F.Mask" "F.Paste")
			(net "GND")
		)
		(pad "E52" smd circle
			(at 9.41324 -11.063224)
			(size 0.3048 0.3048)
			(layers "F.Cu" "F.Mask" "F.Paste")
			(net "PD_CPU_NODE1_BOOTDEVSEL")
		)
		(pad "E54" smd circle
			(at 10.12063 -11.080496)
			(size 0.3048 0.3048)
			(layers "F.Cu" "F.Mask" "F.Paste")
			(net "GND")
		)
		(pad "E55" smd circle
			(at 10.81405 -11.204448)
			(size 0.3048 0.3048)
			(layers "F.Cu" "F.Mask" "F.Paste")
			(net "PCIE_SW_P0_ERR")
		)
		(pad "E57" smd circle
			(at 11.514074 -11.204448)
			(size 0.3048 0.3048)
			(layers "F.Cu" "F.Mask" "F.Paste")
			(net "CPU_NODE1_PROCHOT_N")
		)
		(pad "E58" smd circle
			(at 12.192254 -11.013694)
			(size 0.3048 0.3048)
			(layers "F.Cu" "F.Mask" "F.Paste")
			(net "GND")
		)
		(pad "E59" smd circle
			(at 12.894564 -11.063224)
			(size 0.3048 0.3048)
			(layers "F.Cu" "F.Mask" "F.Paste")
			(net "TP_CPU_E59")
		)
		(pad "E61" smd circle
			(at 13.916152 -11.063224)
			(size 0.3048 0.3048)
			(layers "F.Cu" "F.Mask" "F.Paste")
			(net "GND")
		)
	)
)
